(kicad_pcb
	(version 20260206)
	(generator "pcbnew")
	(generator_version "10.0")
	(general
		(thickness 1.6)
		(legacy_teardrops no)
	)
	(paper "A4")
	(title_block
		(title "01162023_DA0F0TEBIF0_F0T_Expander_BD_F_brd_V02_OCP.brd")
		(comment 1 "Grand Teton / footprints 3245-3250 of 9728")
	)
	(layers
		(0 "F.Cu" signal "TOP")
		(4 "In1.Cu" signal "GND")
		(6 "In2.Cu" signal "VCC")
		(8 "In3.Cu" signal "VCC1")
		(10 "In4.Cu" signal "GND1")
		(12 "In5.Cu" signal "IN1")
		(14 "In6.Cu" signal "GND2")
		(16 "In7.Cu" signal "IN2")
		(18 "In8.Cu" signal "GND3")
		(20 "In9.Cu" signal "IN3")
		(22 "In10.Cu" signal "GND4")
		(24 "In11.Cu" signal "IN4")
		(26 "In12.Cu" signal "GND5")
		(28 "In13.Cu" signal "IN5")
		(30 "In14.Cu" signal "GND6")
		(32 "In15.Cu" signal "IN6")
		(34 "In16.Cu" signal "GND7")
		(2 "B.Cu" signal "BOTTOM")
		(9 "F.Adhes" user "F.Adhesive")
		(11 "B.Adhes" user "B.Adhesive")
		(13 "F.Paste" user "Package Geometry/Pastemask Top")
		(15 "B.Paste" user "Package Geometry/Pastemask Bottom")
		(5 "F.SilkS" user "Ref Des/Silkscreen Top")
		(7 "B.SilkS" user "Ref Des/Silkscreen Bottom")
		(1 "F.Mask" user "Board Geometry/Soldermask Top")
		(3 "B.Mask" user "Board Geometry/Soldermask Bottom")
		(17 "Dwgs.User" user "User.Drawings")
		(19 "Cmts.User" user "User.Comments")
		(21 "Eco1.User" user "User.Eco1")
		(23 "Eco2.User" user "User.Eco2")
		(25 "Edge.Cuts" user "Board Geometry/Outline")
		(27 "Margin" user)
		(31 "F.CrtYd" user "Package Geometry/Place Bound Top")
		(29 "B.CrtYd" user "Package Geometry/Place Bound Bottom")
		(35 "F.Fab" user "Ref Des/Assembly Top")
		(33 "B.Fab" user "Ref Des/Assembly Bottom")
	)
	(footprint ""
		(layer "F.Cu")
		(at 310.443626 -47.92091)
		(property "Reference" "R614"
			(at 0 0 0)
			(layer "F.SilkS")
			(hide yes)
			(effects
				(font
					(size 1.27 1.27)
				)
			)
		)
		(property "Value" ""
			(at 0 0 0)
			(layer "F.Fab")
			(effects
				(font
					(size 1.27 1.27)
				)
			)
		)
		(duplicate_pad_numbers_are_jumpers no)
		(fp_line
			(start -0.7874 -0.4064)
			(end 0.7874 -0.4064)
			(stroke
				(width 0.1524)
				(type default)
			)
			(layer "F.SilkS")
		)
		(fp_line
			(start -0.7874 0.4064)
			(end -0.7874 -0.4064)
			(stroke
				(width 0.1524)
				(type default)
			)
			(layer "F.SilkS")
		)
		(fp_line
			(start 0.7874 -0.4064)
			(end 0.7874 0.4064)
			(stroke
				(width 0.1524)
				(type default)
			)
			(layer "F.SilkS")
		)
		(fp_line
			(start 0.7874 0.4064)
			(end -0.7874 0.4064)
			(stroke
				(width 0.1524)
				(type default)
			)
			(layer "F.SilkS")
		)
		(fp_line
			(start -0.67945 -0.305054)
			(end -0.12065 -0.305054)
			(stroke
				(width 0.1)
				(type default)
			)
			(layer "F.Fab")
		)
		(fp_line
			(start -0.67945 0.3048)
			(end -0.67945 -0.305054)
			(stroke
				(width 0.1)
				(type default)
			)
			(layer "F.Fab")
		)
		(fp_line
			(start -0.12065 -0.305054)
			(end -0.12065 -0.2794)
			(stroke
				(width 0.1)
				(type default)
			)
			(layer "F.Fab")
		)
		(fp_line
			(start -0.12065 -0.2794)
			(end 0.12065 -0.2794)
			(stroke
				(width 0.1)
				(type default)
			)
			(layer "F.Fab")
		)
		(fp_line
			(start -0.12065 0.2794)
			(end -0.12065 0.3048)
			(stroke
				(width 0.1)
				(type default)
			)
			(layer "F.Fab")
		)
		(fp_line
			(start -0.12065 0.3048)
			(end -0.67945 0.3048)
			(stroke
				(width 0.1)
				(type default)
			)
			(layer "F.Fab")
		)
		(fp_line
			(start 0.120396 0.2794)
			(end -0.12065 0.2794)
			(stroke
				(width 0.1)
				(type default)
			)
			(layer "F.Fab")
		)
		(fp_line
			(start 0.120396 0.3048)
			(end 0.120396 0.2794)
			(stroke
				(width 0.1)
				(type default)
			)
			(layer "F.Fab")
		)
		(fp_line
			(start 0.12065 -0.3048)
			(end 0.67945 -0.3048)
			(stroke
				(width 0.1)
				(type default)
			)
			(layer "F.Fab")
		)
		(fp_line
			(start 0.12065 -0.2794)
			(end 0.12065 -0.3048)
			(stroke
				(width 0.1)
				(type default)
			)
			(layer "F.Fab")
		)
		(fp_line
			(start 0.67945 -0.3048)
			(end 0.67945 0.3048)
			(stroke
				(width 0.1)
				(type default)
			)
			(layer "F.Fab")
		)
		(fp_line
			(start 0.67945 0.3048)
			(end 0.120396 0.3048)
			(stroke
				(width 0.1)
				(type default)
			)
			(layer "F.Fab")
		)
		(pad "1" smd circle
			(at -0.40005 0)
			(size 0 0)
			(layers "F.Cu" "F.Mask" "F.Paste")
			(net "P3V3_AUX")
		)
		(pad "2" smd circle
			(at 0.40005 0)
			(size 0 0)
			(layers "F.Cu" "F.Mask" "F.Paste")
			(net "SSD_8_15_ADC_ALERT_N")
		)
	)
	(footprint ""
		(layer "F.Cu")
		(at 175.0949 -102.798372 180)
		(property "Reference" "R172"
			(at 0 0 180)
			(layer "F.SilkS")
			(hide yes)
			(effects
				(font
					(size 1.27 1.27)
				)
			)
		)
		(property "Value" ""
			(at 0 0 180)
			(layer "F.Fab")
			(effects
				(font
					(size 1.27 1.27)
				)
			)
		)
		(duplicate_pad_numbers_are_jumpers no)
		(fp_line
			(start 0.7874 0.4064)
			(end -0.7874 0.4064)
			(stroke
				(width 0.1524)
				(type default)
			)
			(layer "F.SilkS")
		)
		(fp_line
			(start 0.7874 -0.4064)
			(end 0.7874 0.4064)
			(stroke
				(width 0.1524)
				(type default)
			)
			(layer "F.SilkS")
		)
		(fp_line
			(start -0.7874 0.4064)
			(end -0.7874 -0.4064)
			(stroke
				(width 0.1524)
				(type default)
			)
			(layer "F.SilkS")
		)
		(fp_line
			(start -0.7874 -0.4064)
			(end 0.7874 -0.4064)
			(stroke
				(width 0.1524)
				(type default)
			)
			(layer "F.SilkS")
		)
		(fp_line
			(start 0.67945 0.3048)
			(end 0.120396 0.3048)
			(stroke
				(width 0.1)
				(type default)
			)
			(layer "F.Fab")
		)
		(fp_line
			(start 0.67945 -0.3048)
			(end 0.67945 0.3048)
			(stroke
				(width 0.1)
				(type default)
			)
			(layer "F.Fab")
		)
		(fp_line
			(start 0.12065 -0.2794)
			(end 0.12065 -0.3048)
			(stroke
				(width 0.1)
				(type default)
			)
			(layer "F.Fab")
		)
		(fp_line
			(start 0.12065 -0.3048)
			(end 0.67945 -0.3048)
			(stroke
				(width 0.1)
				(type default)
			)
			(layer "F.Fab")
		)
		(fp_line
			(start 0.120396 0.3048)
			(end 0.120396 0.2794)
			(stroke
				(width 0.1)
				(type default)
			)
			(layer "F.Fab")
		)
		(fp_line
			(start 0.120396 0.2794)
			(end -0.12065 0.2794)
			(stroke
				(width 0.1)
				(type default)
			)
			(layer "F.Fab")
		)
		(fp_line
			(start -0.12065 0.3048)
			(end -0.67945 0.3048)
			(stroke
				(width 0.1)
				(type default)
			)
			(layer "F.Fab")
		)
		(fp_line
			(start -0.12065 0.2794)
			(end -0.12065 0.3048)
			(stroke
				(width 0.1)
				(type default)
			)
			(layer "F.Fab")
		)
		(fp_line
			(start -0.12065 -0.2794)
			(end 0.12065 -0.2794)
			(stroke
				(width 0.1)
				(type default)
			)
			(layer "F.Fab")
		)
		(fp_line
			(start -0.12065 -0.305054)
			(end -0.12065 -0.2794)
			(stroke
				(width 0.1)
				(type default)
			)
			(layer "F.Fab")
		)
		(fp_line
			(start -0.67945 0.3048)
			(end -0.67945 -0.305054)
			(stroke
				(width 0.1)
				(type default)
			)
			(layer "F.Fab")
		)
		(fp_line
			(start -0.67945 -0.305054)
			(end -0.12065 -0.305054)
			(stroke
				(width 0.1)
				(type default)
			)
			(layer "F.Fab")
		)
		(pad "1" smd circle
			(at -0.40005 0 180)
			(size 0 0)
			(layers "F.Cu" "F.Mask" "F.Paste")
			(net "NCSI_NIC3_TXD1")
		)
		(pad "2" smd circle
			(at 0.40005 0 180)
			(size 0 0)
			(layers "F.Cu" "F.Mask" "F.Paste")
			(net "GND")
		)
	)
	(footprint ""
		(layer "F.Cu")
		(at 85.103208 -59.571636 90)
		(property "Reference" "PR270"
			(at 0 0 90)
			(layer "F.SilkS")
			(hide yes)
			(effects
				(font
					(size 1.27 1.27)
				)
			)
		)
		(property "Value" ""
			(at 0 0 90)
			(layer "F.Fab")
			(effects
				(font
					(size 1.27 1.27)
				)
			)
		)
		(duplicate_pad_numbers_are_jumpers no)
		(fp_line
			(start 0.7874 -0.4064)
			(end 0.7874 0.4064)
			(stroke
				(width 0.1524)
				(type default)
			)
			(layer "F.SilkS")
		)
		(fp_line
			(start -0.7874 -0.4064)
			(end 0.7874 -0.4064)
			(stroke
				(width 0.1524)
				(type default)
			)
			(layer "F.SilkS")
		)
		(fp_line
			(start 0.7874 0.4064)
			(end -0.7874 0.4064)
			(stroke
				(width 0.1524)
				(type default)
			)
			(layer "F.SilkS")
		)
		(fp_line
			(start -0.7874 0.4064)
			(end -0.7874 -0.4064)
			(stroke
				(width 0.1524)
				(type default)
			)
			(layer "F.SilkS")
		)
		(fp_line
			(start -0.12065 -0.305054)
			(end -0.12065 -0.2794)
			(stroke
				(width 0.1)
				(type default)
			)
			(layer "F.Fab")
		)
		(fp_line
			(start -0.67945 -0.305054)
			(end -0.12065 -0.305054)
			(stroke
				(width 0.1)
				(type default)
			)
			(layer "F.Fab")
		)
		(fp_line
			(start 0.67945 -0.3048)
			(end 0.67945 0.3048)
			(stroke
				(width 0.1)
				(type default)
			)
			(layer "F.Fab")
		)
		(fp_line
			(start 0.12065 -0.3048)
			(end 0.67945 -0.3048)
			(stroke
				(width 0.1)
				(type default)
			)
			(layer "F.Fab")
		)
		(fp_line
			(start 0.12065 -0.2794)
			(end 0.12065 -0.3048)
			(stroke
				(width 0.1)
				(type default)
			)
			(layer "F.Fab")
		)
		(fp_line
			(start -0.12065 -0.2794)
			(end 0.12065 -0.2794)
			(stroke
				(width 0.1)
				(type default)
			)
			(layer "F.Fab")
		)
		(fp_line
			(start 0.120396 0.2794)
			(end -0.12065 0.2794)
			(stroke
				(width 0.1)
				(type default)
			)
			(layer "F.Fab")
		)
		(fp_line
			(start -0.12065 0.2794)
			(end -0.12065 0.3048)
			(stroke
				(width 0.1)
				(type default)
			)
			(layer "F.Fab")
		)
		(fp_line
			(start 0.67945 0.3048)
			(end 0.120396 0.3048)
			(stroke
				(width 0.1)
				(type default)
			)
			(layer "F.Fab")
		)
		(fp_line
			(start 0.120396 0.3048)
			(end 0.120396 0.2794)
			(stroke
				(width 0.1)
				(type default)
			)
			(layer "F.Fab")
		)
		(fp_line
			(start -0.12065 0.3048)
			(end -0.67945 0.3048)
			(stroke
				(width 0.1)
				(type default)
			)
			(layer "F.Fab")
		)
		(fp_line
			(start -0.67945 0.3048)
			(end -0.67945 -0.305054)
			(stroke
				(width 0.1)
				(type default)
			)
			(layer "F.Fab")
		)
		(pad "1" smd circle
			(at -0.40005 0 90)
			(size 0 0)
			(layers "F.Cu" "F.Mask" "F.Paste")
			(net "P3V3_SSD3_OCP")
		)
		(pad "2" smd circle
			(at 0.40005 0 90)
			(size 0 0)
			(layers "F.Cu" "F.Mask" "F.Paste")
			(net "GND")
		)
	)
	(footprint ""
		(layer "F.Cu")
		(at 358.013 -229.616)
		(property "Reference" "R3615"
			(at 0 0 0)
			(layer "F.SilkS")
			(hide yes)
			(effects
				(font
					(size 1.27 1.27)
				)
			)
		)
		(property "Value" ""
			(at 0 0 0)
			(layer "F.Fab")
			(effects
				(font
					(size 1.27 1.27)
				)
			)
		)
		(duplicate_pad_numbers_are_jumpers no)
		(fp_line
			(start -0.7874 -0.4064)
			(end 0.7874 -0.4064)
			(stroke
				(width 0.1524)
				(type default)
			)
			(layer "F.SilkS")
		)
		(fp_line
			(start -0.7874 0.4064)
			(end -0.7874 -0.4064)
			(stroke
				(width 0.1524)
				(type default)
			)
			(layer "F.SilkS")
		)
		(fp_line
			(start 0.7874 -0.4064)
			(end 0.7874 0.4064)
			(stroke
				(width 0.1524)
				(type default)
			)
			(layer "F.SilkS")
		)
		(fp_line
			(start 0.7874 0.4064)
			(end -0.7874 0.4064)
			(stroke
				(width 0.1524)
				(type default)
			)
			(layer "F.SilkS")
		)
		(fp_line
			(start -0.67945 -0.305054)
			(end -0.12065 -0.305054)
			(stroke
				(width 0.1)
				(type default)
			)
			(layer "F.Fab")
		)
		(fp_line
			(start -0.67945 0.3048)
			(end -0.67945 -0.305054)
			(stroke
				(width 0.1)
				(type default)
			)
			(layer "F.Fab")
		)
		(fp_line
			(start -0.12065 -0.305054)
			(end -0.12065 -0.2794)
			(stroke
				(width 0.1)
				(type default)
			)
			(layer "F.Fab")
		)
		(fp_line
			(start -0.12065 -0.2794)
			(end 0.12065 -0.2794)
			(stroke
				(width 0.1)
				(type default)
			)
			(layer "F.Fab")
		)
		(fp_line
			(start -0.12065 0.2794)
			(end -0.12065 0.3048)
			(stroke
				(width 0.1)
				(type default)
			)
			(layer "F.Fab")
		)
		(fp_line
			(start -0.12065 0.3048)
			(end -0.67945 0.3048)
			(stroke
				(width 0.1)
				(type default)
			)
			(layer "F.Fab")
		)
		(fp_line
			(start 0.120396 0.2794)
			(end -0.12065 0.2794)
			(stroke
				(width 0.1)
				(type default)
			)
			(layer "F.Fab")
		)
		(fp_line
			(start 0.120396 0.3048)
			(end 0.120396 0.2794)
			(stroke
				(width 0.1)
				(type default)
			)
			(layer "F.Fab")
		)
		(fp_line
			(start 0.12065 -0.3048)
			(end 0.67945 -0.3048)
			(stroke
				(width 0.1)
				(type default)
			)
			(layer "F.Fab")
		)
		(fp_line
			(start 0.12065 -0.2794)
			(end 0.12065 -0.3048)
			(stroke
				(width 0.1)
				(type default)
			)
			(layer "F.Fab")
		)
		(fp_line
			(start 0.67945 -0.3048)
			(end 0.67945 0.3048)
			(stroke
				(width 0.1)
				(type default)
			)
			(layer "F.Fab")
		)
		(fp_line
			(start 0.67945 0.3048)
			(end 0.120396 0.3048)
			(stroke
				(width 0.1)
				(type default)
			)
			(layer "F.Fab")
		)
		(pad "1" smd circle
			(at -0.40005 0)
			(size 0 0)
			(layers "F.Cu" "F.Mask" "F.Paste")
			(net "RST_NIC1_PERST_N")
		)
		(pad "2" smd circle
			(at 0.40005 0)
			(size 0 0)
			(layers "F.Cu" "F.Mask" "F.Paste")
			(net "RST_NIC1_PERST_R_N")
		)
	)
	(footprint ""
		(layer "F.Cu")
		(at 264.582402 -332.609698)
		(property "Reference" "R6795"
			(at 0 0 0)
			(layer "F.SilkS")
			(hide yes)
			(effects
				(font
					(size 1.27 1.27)
				)
			)
		)
		(property "Value" ""
			(at 0 0 0)
			(layer "F.Fab")
			(effects
				(font
					(size 1.27 1.27)
				)
			)
		)
		(duplicate_pad_numbers_are_jumpers no)
		(fp_line
			(start -0.7874 -0.4064)
			(end 0.7874 -0.4064)
			(stroke
				(width 0.1524)
				(type default)
			)
			(layer "F.SilkS")
		)
		(fp_line
			(start -0.7874 0.4064)
			(end -0.7874 -0.4064)
			(stroke
				(width 0.1524)
				(type default)
			)
			(layer "F.SilkS")
		)
		(fp_line
			(start 0.7874 -0.4064)
			(end 0.7874 0.4064)
			(stroke
				(width 0.1524)
				(type default)
			)
			(layer "F.SilkS")
		)
		(fp_line
			(start 0.7874 0.4064)
			(end -0.7874 0.4064)
			(stroke
				(width 0.1524)
				(type default)
			)
			(layer "F.SilkS")
		)
		(fp_line
			(start -0.67945 -0.305054)
			(end -0.12065 -0.305054)
			(stroke
				(width 0.1)
				(type default)
			)
			(layer "F.Fab")
		)
		(fp_line
			(start -0.67945 0.3048)
			(end -0.67945 -0.305054)
			(stroke
				(width 0.1)
				(type default)
			)
			(layer "F.Fab")
		)
		(fp_line
			(start -0.12065 -0.305054)
			(end -0.12065 -0.2794)
			(stroke
				(width 0.1)
				(type default)
			)
			(layer "F.Fab")
		)
		(fp_line
			(start -0.12065 -0.2794)
			(end 0.12065 -0.2794)
			(stroke
				(width 0.1)
				(type default)
			)
			(layer "F.Fab")
		)
		(fp_line
			(start -0.12065 0.2794)
			(end -0.12065 0.3048)
			(stroke
				(width 0.1)
				(type default)
			)
			(layer "F.Fab")
		)
		(fp_line
			(start -0.12065 0.3048)
			(end -0.67945 0.3048)
			(stroke
				(width 0.1)
				(type default)
			)
			(layer "F.Fab")
		)
		(fp_line
			(start 0.120396 0.2794)
			(end -0.12065 0.2794)
			(stroke
				(width 0.1)
				(type default)
			)
			(layer "F.Fab")
		)
		(fp_line
			(start 0.120396 0.3048)
			(end 0.120396 0.2794)
			(stroke
				(width 0.1)
				(type default)
			)
			(layer "F.Fab")
		)
		(fp_line
			(start 0.12065 -0.3048)
			(end 0.67945 -0.3048)
			(stroke
				(width 0.1)
				(type default)
			)
			(layer "F.Fab")
		)
		(fp_line
			(start 0.12065 -0.2794)
			(end 0.12065 -0.3048)
			(stroke
				(width 0.1)
				(type default)
			)
			(layer "F.Fab")
		)
		(fp_line
			(start 0.67945 -0.3048)
			(end 0.67945 0.3048)
			(stroke
				(width 0.1)
				(type default)
			)
			(layer "F.Fab")
		)
		(fp_line
			(start 0.67945 0.3048)
			(end 0.120396 0.3048)
			(stroke
				(width 0.1)
				(type default)
			)
			(layer "F.Fab")
		)
		(pad "1" smd circle
			(at -0.40005 0)
			(size 0 0)
			(layers "F.Cu" "F.Mask" "F.Paste")
			(net "HSC_OC_VOL")
		)
		(pad "2" smd circle
			(at 0.40005 0)
			(size 0 0)
			(layers "F.Cu" "F.Mask" "F.Paste")
			(net "HSC_D_OC_R2")
		)
	)
	(footprint ""
		(layer "F.Cu")
		(at 106.091228 -268.278102 -90)
		(property "Reference" "PC982"
			(at 0 0 270)
			(layer "F.SilkS")
			(hide yes)
			(effects
				(font
					(size 1.27 1.27)
				)
			)
		)
		(property "Value" ""
			(at 0 0 270)
			(layer "F.Fab")
			(effects
				(font
					(size 1.27 1.27)
				)
			)
		)
		(duplicate_pad_numbers_are_jumpers no)
		(fp_line
			(start -0.7874 0.4064)
			(end -0.7874 -0.4064)
			(stroke
				(width 0.1524)
				(type default)
			)
			(layer "F.SilkS")
		)
		(fp_line
			(start 0.7874 0.4064)
			(end -0.7874 0.4064)
			(stroke
				(width 0.1524)
				(type default)
			)
			(layer "F.SilkS")
		)
		(fp_line
			(start -0.7874 -0.4064)
			(end 0.7874 -0.4064)
			(stroke
				(width 0.1524)
				(type default)
			)
			(layer "F.SilkS")
		)
		(fp_line
			(start 0.7874 -0.4064)
			(end 0.7874 0.4064)
			(stroke
				(width 0.1524)
				(type default)
			)
			(layer "F.SilkS")
		)
		(fp_line
			(start -0.67945 0.3048)
			(end -0.67945 -0.305054)
			(stroke
				(width 0.1)
				(type default)
			)
			(layer "F.Fab")
		)
		(fp_line
			(start -0.12065 0.3048)
			(end -0.67945 0.3048)
			(stroke
				(width 0.1)
				(type default)
			)
			(layer "F.Fab")
		)
		(fp_line
			(start 0.120396 0.3048)
			(end 0.120396 0.2794)
			(stroke
				(width 0.1)
				(type default)
			)
			(layer "F.Fab")
		)
		(fp_line
			(start 0.67945 0.3048)
			(end 0.120396 0.3048)
			(stroke
				(width 0.1)
				(type default)
			)
			(layer "F.Fab")
		)
		(fp_line
			(start -0.12065 0.2794)
			(end -0.12065 0.3048)
			(stroke
				(width 0.1)
				(type default)
			)
			(layer "F.Fab")
		)
		(fp_line
			(start 0.120396 0.2794)
			(end -0.12065 0.2794)
			(stroke
				(width 0.1)
				(type default)
			)
			(layer "F.Fab")
		)
		(fp_line
			(start -0.12065 -0.2794)
			(end 0.12065 -0.2794)
			(stroke
				(width 0.1)
				(type default)
			)
			(layer "F.Fab")
		)
		(fp_line
			(start 0.12065 -0.2794)
			(end 0.12065 -0.3048)
			(stroke
				(width 0.1)
				(type default)
			)
			(layer "F.Fab")
		)
		(fp_line
			(start 0.12065 -0.3048)
			(end 0.67945 -0.3048)
			(stroke
				(width 0.1)
				(type default)
			)
			(layer "F.Fab")
		)
		(fp_line
			(start 0.67945 -0.3048)
			(end 0.67945 0.3048)
			(stroke
				(width 0.1)
				(type default)
			)
			(layer "F.Fab")
		)
		(fp_line
			(start -0.67945 -0.305054)
			(end -0.12065 -0.305054)
			(stroke
				(width 0.1)
				(type default)
			)
			(layer "F.Fab")
		)
		(fp_line
			(start -0.12065 -0.305054)
			(end -0.12065 -0.2794)
			(stroke
				(width 0.1)
				(type default)
			)
			(layer "F.Fab")
		)
		(pad "1" smd circle
			(at -0.40005 0 270)
			(size 0 0)
			(layers "F.Cu" "F.Mask" "F.Paste")
			(net "P12V_AUX")
		)
		(pad "2" smd circle
			(at 0.40005 0 270)
			(size 0 0)
			(layers "F.Cu" "F.Mask" "F.Paste")
			(net "GND")
		)
	)
)
